(kicad_pcb
	(version 20260206)
	(generator "pcbnew")
	(generator_version "10.0")
	(general
		(thickness 1.6)
		(legacy_teardrops no)
	)
	(paper "A4")
	(title_block
		(title "04192023_DAF0TMB3IC0_F0TG_MB_C_brd_V02_OCP.brd")
		(comment 1 "Grand Teton / footprint 2929 of 8354 (J38), pads 1-109 of 175")
	)
	(layers
		(0 "F.Cu" signal "TOP")
		(4 "In1.Cu" signal "GND")
		(6 "In2.Cu" signal "IN1")
		(8 "In3.Cu" signal "GND1")
		(10 "In4.Cu" signal "IN2")
		(12 "In5.Cu" signal "GND2")
		(14 "In6.Cu" signal "IN3")
		(16 "In7.Cu" signal "GND3")
		(18 "In8.Cu" signal "VCC")
		(20 "In9.Cu" signal "VCC1")
		(22 "In10.Cu" signal "GND4")
		(24 "In11.Cu" signal "IN4")
		(26 "In12.Cu" signal "GND5")
		(28 "In13.Cu" signal "IN5")
		(30 "In14.Cu" signal "GND6")
		(32 "In15.Cu" signal "IN6")
		(34 "In16.Cu" signal "GND7")
		(2 "B.Cu" signal "BOTTOM")
		(9 "F.Adhes" user "F.Adhesive")
		(11 "B.Adhes" user "B.Adhesive")
		(13 "F.Paste" user "Package Geometry/Pastemask Top")
		(15 "B.Paste" user "Package Geometry/Pastemask Bottom")
		(5 "F.SilkS" user "Ref Des/Silkscreen Top")
		(7 "B.SilkS" user "Ref Des/Silkscreen Bottom")
		(1 "F.Mask" user "Board Geometry/Soldermask Top")
		(3 "B.Mask" user "Board Geometry/Soldermask Bottom")
		(17 "Dwgs.User" user "User.Drawings")
		(19 "Cmts.User" user "User.Comments")
		(21 "Eco1.User" user "User.Eco1")
		(23 "Eco2.User" user "User.Eco2")
		(25 "Edge.Cuts" user "Board Geometry/Outline")
		(27 "Margin" user)
		(31 "F.CrtYd" user "Package Geometry/Place Bound Top")
		(29 "B.CrtYd" user "Package Geometry/Place Bound Bottom")
		(35 "F.Fab" user "Ref Des/Assembly Top")
		(33 "B.Fab" user "Ref Des/Assembly Bottom")
	)
	(footprint ""
		(layer "F.Cu")
		(at 421.901874 -5.569966 -90)
		(property "Reference" "J38"
			(at -8.103616 -20.50034 0)
			(unlocked yes)
			(layer "F.SilkS")
			(effects
				(font
					(size 0.7874 0.5842)
					(thickness 0.1524)
				)
				(justify left)
			)
		)
		(property "Value" ""
			(at 0 0 270)
			(layer "F.Fab")
			(effects
				(font
					(size 1.27 1.27)
				)
			)
		)
		(duplicate_pad_numbers_are_jumpers no)
		(pad "" np_thru_hole circle
			(at -0.599948 -32.079946 180)
			(size 1.1176 1.1176)
			(drill 1.1176)
			(layers "*.Cu" "*.Mask")
			(clearance 0.381)
			(thermal_gap 0.381)
		)
		(pad "" np_thru_hole circle
			(at 0.40005 32.085026 180)
			(size 1.1176 1.1176)
			(drill 1.1176)
			(layers "*.Cu" "*.Mask")
			(clearance 0.381)
			(thermal_gap 0.381)
		)
		(pad "A1" smd rect
			(at -2.750058 -18.465038 180)
			(size 0.381 1.4478)
			(layers "F.Cu" "F.Mask" "F.Paste")
			(net "GND")
		)
		(pad "A2" smd rect
			(at -2.750058 -17.86509 180)
			(size 0.381 1.4478)
			(layers "F.Cu" "F.Mask" "F.Paste")
			(net "GND")
		)
		(pad "A3" smd rect
			(at -2.750058 -17.264888 180)
			(size 0.381 1.4478)
			(layers "F.Cu" "F.Mask" "F.Paste")
			(net "GND")
		)
		(pad "A4" smd rect
			(at -2.750058 -16.66494 180)
			(size 0.381 1.4478)
			(layers "F.Cu" "F.Mask" "F.Paste")
			(net "GND")
		)
		(pad "A5" smd rect
			(at -2.750058 -16.064992 180)
			(size 0.381 1.4478)
			(layers "F.Cu" "F.Mask" "F.Paste")
			(net "GND")
		)
		(pad "A6" smd rect
			(at -2.750058 -15.465044 180)
			(size 0.381 1.4478)
			(layers "F.Cu" "F.Mask" "F.Paste")
			(net "GND")
		)
		(pad "A7" smd rect
			(at -2.750058 -14.865096 180)
			(size 0.381 1.4478)
			(layers "F.Cu" "F.Mask" "F.Paste")
			(net "SMB_OCP_SFF_3V3AUX_BUF_R_SCL")
		)
		(pad "A8" smd rect
			(at -2.750058 -14.264894 180)
			(size 0.381 1.4478)
			(layers "F.Cu" "F.Mask" "F.Paste")
			(net "SMB_OCP_SFF_3V3AUX_BUF_R_SDA")
		)
		(pad "A9" smd rect
			(at -2.750058 -13.664946 180)
			(size 0.381 1.4478)
			(layers "F.Cu" "F.Mask" "F.Paste")
			(net "RST_SMB_OCP_SFF_N")
		)
		(pad "A10" smd rect
			(at -2.750058 -13.064998 180)
			(size 0.381 1.4478)
			(layers "F.Cu" "F.Mask" "F.Paste")
			(net "OCP_SFF_PRSNTA_R_N")
		)
		(pad "A11" smd rect
			(at -2.750058 -12.46505 180)
			(size 0.381 1.4478)
			(layers "F.Cu" "F.Mask" "F.Paste")
			(net "RST_PERST1_OCP_SFF_N")
		)
		(pad "A12" smd rect
			(at -2.750058 -11.865102 180)
			(size 0.381 1.4478)
			(layers "F.Cu" "F.Mask" "F.Paste")
			(net "OCP_SFF_PRSNT2_R_N")
		)
		(pad "A13" smd rect
			(at -2.750058 -11.2649 180)
			(size 0.381 1.4478)
			(layers "F.Cu" "F.Mask" "F.Paste")
			(net "GND")
		)
		(pad "A14" smd rect
			(at -2.750058 -10.664952 180)
			(size 0.381 1.4478)
			(layers "F.Cu" "F.Mask" "F.Paste")
			(net "CLK_100M_CPU0_CLK03_DN")
		)
		(pad "A15" smd rect
			(at -2.750058 -10.065004 180)
			(size 0.381 1.4478)
			(layers "F.Cu" "F.Mask" "F.Paste")
			(net "CLK_100M_CPU0_CLK03_DP")
		)
		(pad "A16" smd rect
			(at -2.750058 -9.465056 180)
			(size 0.381 1.4478)
			(layers "F.Cu" "F.Mask" "F.Paste")
			(net "GND")
		)
		(pad "A17" smd rect
			(at -2.750058 -8.865108 180)
			(size 0.381 1.4478)
			(layers "F.Cu" "F.Mask" "F.Paste")
			(net "P5E_CPU0_G3_RX_DN<0>")
		)
		(pad "A18" smd rect
			(at -2.750058 -8.264906 180)
			(size 0.381 1.4478)
			(layers "F.Cu" "F.Mask" "F.Paste")
			(net "P5E_CPU0_G3_RX_DP<0>")
		)
		(pad "A19" smd rect
			(at -2.750058 -7.664958 180)
			(size 0.381 1.4478)
			(layers "F.Cu" "F.Mask" "F.Paste")
			(net "GND")
		)
		(pad "A20" smd rect
			(at -2.750058 -7.06501 180)
			(size 0.381 1.4478)
			(layers "F.Cu" "F.Mask" "F.Paste")
			(net "P5E_CPU0_G3_RX_DN<1>")
		)
		(pad "A21" smd rect
			(at -2.750058 -6.465062 180)
			(size 0.381 1.4478)
			(layers "F.Cu" "F.Mask" "F.Paste")
			(net "P5E_CPU0_G3_RX_DP<1>")
		)
		(pad "A22" smd rect
			(at -2.750058 -5.865114 180)
			(size 0.381 1.4478)
			(layers "F.Cu" "F.Mask" "F.Paste")
			(net "GND")
		)
		(pad "A23" smd rect
			(at -2.750058 -5.264912 180)
			(size 0.381 1.4478)
			(layers "F.Cu" "F.Mask" "F.Paste")
			(net "P5E_CPU0_G3_RX_DN<2>")
		)
		(pad "A24" smd rect
			(at -2.750058 -4.664964 180)
			(size 0.381 1.4478)
			(layers "F.Cu" "F.Mask" "F.Paste")
			(net "P5E_CPU0_G3_RX_DP<2>")
		)
		(pad "A25" smd rect
			(at -2.750058 -4.065016 180)
			(size 0.381 1.4478)
			(layers "F.Cu" "F.Mask" "F.Paste")
			(net "GND")
		)
		(pad "A26" smd rect
			(at -2.750058 -3.465068 180)
			(size 0.381 1.4478)
			(layers "F.Cu" "F.Mask" "F.Paste")
			(net "P5E_CPU0_G3_RX_DN<3>")
		)
		(pad "A27" smd rect
			(at -2.750058 -2.86512 180)
			(size 0.381 1.4478)
			(layers "F.Cu" "F.Mask" "F.Paste")
			(net "P5E_CPU0_G3_RX_DP<3>")
		)
		(pad "A28" smd rect
			(at -2.750058 -2.264918 180)
			(size 0.381 1.4478)
			(layers "F.Cu" "F.Mask" "F.Paste")
			(net "GND")
		)
		(pad "A29" smd rect
			(at -2.750058 1.74498 180)
			(size 0.381 1.4478)
			(layers "F.Cu" "F.Mask" "F.Paste")
			(net "GND")
		)
		(pad "A30" smd rect
			(at -2.750058 2.344928 180)
			(size 0.381 1.4478)
			(layers "F.Cu" "F.Mask" "F.Paste")
			(net "P5E_CPU0_G3_RX_DN<4>")
		)
		(pad "A31" smd rect
			(at -2.750058 2.944876 180)
			(size 0.381 1.4478)
			(layers "F.Cu" "F.Mask" "F.Paste")
			(net "P5E_CPU0_G3_RX_DP<4>")
		)
		(pad "A32" smd rect
			(at -2.750058 3.545078 180)
			(size 0.381 1.4478)
			(layers "F.Cu" "F.Mask" "F.Paste")
			(net "GND")
		)
		(pad "A33" smd rect
			(at -2.750058 4.145026 180)
			(size 0.381 1.4478)
			(layers "F.Cu" "F.Mask" "F.Paste")
			(net "P5E_CPU0_G3_RX_DN<5>")
		)
		(pad "A34" smd rect
			(at -2.750058 4.744974 180)
			(size 0.381 1.4478)
			(layers "F.Cu" "F.Mask" "F.Paste")
			(net "P5E_CPU0_G3_RX_DP<5>")
		)
		(pad "A35" smd rect
			(at -2.750058 5.344922 180)
			(size 0.381 1.4478)
			(layers "F.Cu" "F.Mask" "F.Paste")
			(net "GND")
		)
		(pad "A36" smd rect
			(at -2.750058 5.945124 180)
			(size 0.381 1.4478)
			(layers "F.Cu" "F.Mask" "F.Paste")
			(net "P5E_CPU0_G3_RX_DN<6>")
		)
		(pad "A37" smd rect
			(at -2.750058 6.545072 180)
			(size 0.381 1.4478)
			(layers "F.Cu" "F.Mask" "F.Paste")
			(net "P5E_CPU0_G3_RX_DP<6>")
		)
		(pad "A38" smd rect
			(at -2.750058 7.14502 180)
			(size 0.381 1.4478)
			(layers "F.Cu" "F.Mask" "F.Paste")
			(net "GND")
		)
		(pad "A39" smd rect
			(at -2.750058 7.744968 180)
			(size 0.381 1.4478)
			(layers "F.Cu" "F.Mask" "F.Paste")
			(net "P5E_CPU0_G3_RX_DN<7>")
		)
		(pad "A40" smd rect
			(at -2.750058 8.344916 180)
			(size 0.381 1.4478)
			(layers "F.Cu" "F.Mask" "F.Paste")
			(net "P5E_CPU0_G3_RX_DP<7>")
		)
		(pad "A41" smd rect
			(at -2.750058 8.945118 180)
			(size 0.381 1.4478)
			(layers "F.Cu" "F.Mask" "F.Paste")
			(net "GND")
		)
		(pad "A42" smd rect
			(at -2.750058 9.545066 180)
			(size 0.381 1.4478)
			(layers "F.Cu" "F.Mask" "F.Paste")
			(net "OCP_SFF_PRSNT1_R_N")
		)
		(pad "A43" smd rect
			(at -2.750058 14.454886 180)
			(size 0.381 1.4478)
			(layers "F.Cu" "F.Mask" "F.Paste")
			(net "GND")
		)
		(pad "A44" smd rect
			(at -2.750058 15.055088 180)
			(size 0.381 1.4478)
			(layers "F.Cu" "F.Mask" "F.Paste")
			(net "P5E_CPU0_G3_RX_DN<8>")
		)
		(pad "A45" smd rect
			(at -2.750058 15.655036 180)
			(size 0.381 1.4478)
			(layers "F.Cu" "F.Mask" "F.Paste")
			(net "P5E_CPU0_G3_RX_DP<8>")
		)
		(pad "A46" smd rect
			(at -2.750058 16.254984 180)
			(size 0.381 1.4478)
			(layers "F.Cu" "F.Mask" "F.Paste")
			(net "GND")
		)
		(pad "A47" smd rect
			(at -2.750058 16.854932 180)
			(size 0.381 1.4478)
			(layers "F.Cu" "F.Mask" "F.Paste")
			(net "P5E_CPU0_G3_RX_DN<9>")
		)
		(pad "A48" smd rect
			(at -2.750058 17.45488 180)
			(size 0.381 1.4478)
			(layers "F.Cu" "F.Mask" "F.Paste")
			(net "P5E_CPU0_G3_RX_DP<9>")
		)
		(pad "A49" smd rect
			(at -2.750058 18.055082 180)
			(size 0.381 1.4478)
			(layers "F.Cu" "F.Mask" "F.Paste")
			(net "GND")
		)
		(pad "A50" smd rect
			(at -2.750058 18.65503 180)
			(size 0.381 1.4478)
			(layers "F.Cu" "F.Mask" "F.Paste")
			(net "P5E_CPU0_G3_RX_DN<10>")
		)
		(pad "A51" smd rect
			(at -2.750058 19.254978 180)
			(size 0.381 1.4478)
			(layers "F.Cu" "F.Mask" "F.Paste")
			(net "P5E_CPU0_G3_RX_DP<10>")
		)
		(pad "A52" smd rect
			(at -2.750058 19.854926 180)
			(size 0.381 1.4478)
			(layers "F.Cu" "F.Mask" "F.Paste")
			(net "GND")
		)
		(pad "A53" smd rect
			(at -2.750058 20.455128 180)
			(size 0.381 1.4478)
			(layers "F.Cu" "F.Mask" "F.Paste")
			(net "P5E_CPU0_G3_RX_DN<11>")
		)
		(pad "A54" smd rect
			(at -2.750058 21.055076 180)
			(size 0.381 1.4478)
			(layers "F.Cu" "F.Mask" "F.Paste")
			(net "P5E_CPU0_G3_RX_DP<11>")
		)
		(pad "A55" smd rect
			(at -2.750058 21.655024 180)
			(size 0.381 1.4478)
			(layers "F.Cu" "F.Mask" "F.Paste")
			(net "GND")
		)
		(pad "A56" smd rect
			(at -2.750058 22.254972 180)
			(size 0.381 1.4478)
			(layers "F.Cu" "F.Mask" "F.Paste")
			(net "P5E_CPU0_G3_RX_DN<12>")
		)
		(pad "A57" smd rect
			(at -2.750058 22.85492 180)
			(size 0.381 1.4478)
			(layers "F.Cu" "F.Mask" "F.Paste")
			(net "P5E_CPU0_G3_RX_DP<12>")
		)
		(pad "A58" smd rect
			(at -2.750058 23.455122 180)
			(size 0.381 1.4478)
			(layers "F.Cu" "F.Mask" "F.Paste")
			(net "GND")
		)
		(pad "A59" smd rect
			(at -2.750058 24.05507 180)
			(size 0.381 1.4478)
			(layers "F.Cu" "F.Mask" "F.Paste")
			(net "P5E_CPU0_G3_RX_DN<13>")
		)
		(pad "A60" smd rect
			(at -2.750058 24.655018 180)
			(size 0.381 1.4478)
			(layers "F.Cu" "F.Mask" "F.Paste")
			(net "P5E_CPU0_G3_RX_DP<13>")
		)
		(pad "A61" smd rect
			(at -2.750058 25.254966 180)
			(size 0.381 1.4478)
			(layers "F.Cu" "F.Mask" "F.Paste")
			(net "GND")
		)
		(pad "A62" smd rect
			(at -2.750058 25.854914 180)
			(size 0.381 1.4478)
			(layers "F.Cu" "F.Mask" "F.Paste")
			(net "P5E_CPU0_G3_RX_DN<14>")
		)
		(pad "A63" smd rect
			(at -2.750058 26.455116 180)
			(size 0.381 1.4478)
			(layers "F.Cu" "F.Mask" "F.Paste")
			(net "P5E_CPU0_G3_RX_DP<14>")
		)
		(pad "A64" smd rect
			(at -2.750058 27.055064 180)
			(size 0.381 1.4478)
			(layers "F.Cu" "F.Mask" "F.Paste")
			(net "GND")
		)
		(pad "A65" smd rect
			(at -2.750058 27.655012 180)
			(size 0.381 1.4478)
			(layers "F.Cu" "F.Mask" "F.Paste")
			(net "P5E_CPU0_G3_RX_DN<15>")
		)
		(pad "A66" smd rect
			(at -2.750058 28.25496 180)
			(size 0.381 1.4478)
			(layers "F.Cu" "F.Mask" "F.Paste")
			(net "P5E_CPU0_G3_RX_DP<15>")
		)
		(pad "A67" smd rect
			(at -2.750058 28.854908 180)
			(size 0.381 1.4478)
			(layers "F.Cu" "F.Mask" "F.Paste")
			(net "GND")
		)
		(pad "A68" smd rect
			(at -2.750058 29.45511 180)
			(size 0.381 1.4478)
			(layers "F.Cu" "F.Mask" "F.Paste")
			(net "USB2_P11_DN")
		)
		(pad "A69" smd rect
			(at -2.750058 30.055058 180)
			(size 0.381 1.4478)
			(layers "F.Cu" "F.Mask" "F.Paste")
			(net "USB2_P11_DP")
		)
		(pad "A70" smd rect
			(at -2.750058 30.655006 180)
			(size 0.381 1.4478)
			(layers "F.Cu" "F.Mask" "F.Paste")
			(net "OCP_SFF_PWRBRK_N")
		)
		(pad "B1" smd rect
			(at -5.700014 -18.465038 180)
			(size 0.381 1.4478)
			(layers "F.Cu" "F.Mask" "F.Paste")
			(net "P12V_OCP_SFF_R")
		)
		(pad "B2" smd rect
			(at -5.700014 -17.86509 180)
			(size 0.381 1.4478)
			(layers "F.Cu" "F.Mask" "F.Paste")
			(net "P12V_OCP_SFF_R")
		)
		(pad "B3" smd rect
			(at -5.700014 -17.264888 180)
			(size 0.381 1.4478)
			(layers "F.Cu" "F.Mask" "F.Paste")
			(net "P12V_OCP_SFF_R")
		)
		(pad "B4" smd rect
			(at -5.700014 -16.66494 180)
			(size 0.381 1.4478)
			(layers "F.Cu" "F.Mask" "F.Paste")
			(net "P12V_OCP_SFF_R")
		)
		(pad "B5" smd rect
			(at -5.700014 -16.064992 180)
			(size 0.381 1.4478)
			(layers "F.Cu" "F.Mask" "F.Paste")
			(net "P12V_OCP_SFF_R")
		)
		(pad "B6" smd rect
			(at -5.700014 -15.465044 180)
			(size 0.381 1.4478)
			(layers "F.Cu" "F.Mask" "F.Paste")
			(net "P12V_OCP_SFF_R")
		)
		(pad "B7" smd rect
			(at -5.700014 -14.865096 180)
			(size 0.381 1.4478)
			(layers "F.Cu" "F.Mask" "F.Paste")
			(net "OCP_SFF_BIF0_R_N")
		)
		(pad "B8" smd rect
			(at -5.700014 -14.264894 180)
			(size 0.381 1.4478)
			(layers "F.Cu" "F.Mask" "F.Paste")
			(net "OCP_SFF_BIF1_R_N")
		)
		(pad "B9" smd rect
			(at -5.700014 -13.664946 180)
			(size 0.381 1.4478)
			(layers "F.Cu" "F.Mask" "F.Paste")
			(net "OCP_SFF_BIF2_R_N")
		)
		(pad "B10" smd rect
			(at -5.700014 -13.064998 180)
			(size 0.381 1.4478)
			(layers "F.Cu" "F.Mask" "F.Paste")
			(net "RST_PERST0_OCP_SFF_N")
		)
		(pad "B11" smd rect
			(at -5.700014 -12.46505 180)
			(size 0.381 1.4478)
			(layers "F.Cu" "F.Mask" "F.Paste")
			(net "P3V3_OCP_SFF")
		)
		(pad "B12" smd rect
			(at -5.700014 -11.865102 180)
			(size 0.381 1.4478)
			(layers "F.Cu" "F.Mask" "F.Paste")
			(net "OCP_SFF_AUX_PWR_EN_R")
		)
		(pad "B13" smd rect
			(at -5.700014 -11.2649 180)
			(size 0.381 1.4478)
			(layers "F.Cu" "F.Mask" "F.Paste")
			(net "GND")
		)
		(pad "B14" smd rect
			(at -5.700014 -10.664952 180)
			(size 0.381 1.4478)
			(layers "F.Cu" "F.Mask" "F.Paste")
			(net "CLK_100M_CPU0_CLK02_DN")
		)
		(pad "B15" smd rect
			(at -5.700014 -10.065004 180)
			(size 0.381 1.4478)
			(layers "F.Cu" "F.Mask" "F.Paste")
			(net "CLK_100M_CPU0_CLK02_DP")
		)
		(pad "B16" smd rect
			(at -5.700014 -9.465056 180)
			(size 0.381 1.4478)
			(layers "F.Cu" "F.Mask" "F.Paste")
			(net "GND")
		)
		(pad "B17" smd rect
			(at -5.700014 -8.865108 180)
			(size 0.381 1.4478)
			(layers "F.Cu" "F.Mask" "F.Paste")
			(net "P5E_CPU0_G3_TX_C_DP<0>")
		)
		(pad "B18" smd rect
			(at -5.700014 -8.264906 180)
			(size 0.381 1.4478)
			(layers "F.Cu" "F.Mask" "F.Paste")
			(net "P5E_CPU0_G3_TX_C_DN<0>")
		)
		(pad "B19" smd rect
			(at -5.700014 -7.664958 180)
			(size 0.381 1.4478)
			(layers "F.Cu" "F.Mask" "F.Paste")
			(net "GND")
		)
		(pad "B20" smd rect
			(at -5.700014 -7.06501 180)
			(size 0.381 1.4478)
			(layers "F.Cu" "F.Mask" "F.Paste")
			(net "P5E_CPU0_G3_TX_C_DP<1>")
		)
		(pad "B21" smd rect
			(at -5.700014 -6.465062 180)
			(size 0.381 1.4478)
			(layers "F.Cu" "F.Mask" "F.Paste")
			(net "P5E_CPU0_G3_TX_C_DN<1>")
		)
		(pad "B22" smd rect
			(at -5.700014 -5.865114 180)
			(size 0.381 1.4478)
			(layers "F.Cu" "F.Mask" "F.Paste")
			(net "GND")
		)
		(pad "B23" smd rect
			(at -5.700014 -5.264912 180)
			(size 0.381 1.4478)
			(layers "F.Cu" "F.Mask" "F.Paste")
			(net "P5E_CPU0_G3_TX_C_DP<2>")
		)
		(pad "B24" smd rect
			(at -5.700014 -4.664964 180)
			(size 0.381 1.4478)
			(layers "F.Cu" "F.Mask" "F.Paste")
			(net "P5E_CPU0_G3_TX_C_DN<2>")
		)
		(pad "B25" smd rect
			(at -5.700014 -4.065016 180)
			(size 0.381 1.4478)
			(layers "F.Cu" "F.Mask" "F.Paste")
			(net "GND")
		)
		(pad "B26" smd rect
			(at -5.700014 -3.465068 180)
			(size 0.381 1.4478)
			(layers "F.Cu" "F.Mask" "F.Paste")
			(net "P5E_CPU0_G3_TX_C_DP<3>")
		)
		(pad "B27" smd rect
			(at -5.700014 -2.86512 180)
			(size 0.381 1.4478)
			(layers "F.Cu" "F.Mask" "F.Paste")
			(net "P5E_CPU0_G3_TX_C_DN<3>")
		)
		(pad "B28" smd rect
			(at -5.700014 -2.264918 180)
			(size 0.381 1.4478)
			(layers "F.Cu" "F.Mask" "F.Paste")
			(net "GND")
		)
		(pad "B29" smd rect
			(at -5.700014 1.74498 180)
			(size 0.381 1.4478)
			(layers "F.Cu" "F.Mask" "F.Paste")
			(net "GND")
		)
		(pad "B30" smd rect
			(at -5.700014 2.344928 180)
			(size 0.381 1.4478)
			(layers "F.Cu" "F.Mask" "F.Paste")
			(net "P5E_CPU0_G3_TX_C_DP<4>")
		)
		(pad "B31" smd rect
			(at -5.700014 2.944876 180)
			(size 0.381 1.4478)
			(layers "F.Cu" "F.Mask" "F.Paste")
			(net "P5E_CPU0_G3_TX_C_DN<4>")
		)
		(pad "B32" smd rect
			(at -5.700014 3.545078 180)
			(size 0.381 1.4478)
			(layers "F.Cu" "F.Mask" "F.Paste")
			(net "GND")
		)
		(pad "B33" smd rect
			(at -5.700014 4.145026 180)
			(size 0.381 1.4478)
			(layers "F.Cu" "F.Mask" "F.Paste")
			(net "P5E_CPU0_G3_TX_C_DP<5>")
		)
		(pad "B34" smd rect
			(at -5.700014 4.744974 180)
			(size 0.381 1.4478)
			(layers "F.Cu" "F.Mask" "F.Paste")
			(net "P5E_CPU0_G3_TX_C_DN<5>")
		)
		(pad "B35" smd rect
			(at -5.700014 5.344922 180)
			(size 0.381 1.4478)
			(layers "F.Cu" "F.Mask" "F.Paste")
			(net "GND")
		)
		(pad "B36" smd rect
			(at -5.700014 5.945124 180)
			(size 0.381 1.4478)
			(layers "F.Cu" "F.Mask" "F.Paste")
			(net "P5E_CPU0_G3_TX_C_DP<6>")
		)
		(pad "B37" smd rect
			(at -5.700014 6.545072 180)
			(size 0.381 1.4478)
			(layers "F.Cu" "F.Mask" "F.Paste")
			(net "P5E_CPU0_G3_TX_C_DN<6>")
		)
	)
)
